(kicad_pcb
	(version 20260206)
	(generator "pcbnew")
	(generator_version "10.0")
	(general
		(thickness 1.6)
		(legacy_teardrops no)
	)
	(paper "A4")
	(title_block
		(title "01162023_DA0F0TEBIF0_F0T_Expander_BD_F_brd_V02_OCP.brd")
		(comment 1 "Grand Teton / footprint 4451 of 9728 (PEX3), pads 1537-1653 of 2397")
	)
	(layers
		(0 "F.Cu" signal "TOP")
		(4 "In1.Cu" signal "GND")
		(6 "In2.Cu" signal "VCC")
		(8 "In3.Cu" signal "VCC1")
		(10 "In4.Cu" signal "GND1")
		(12 "In5.Cu" signal "IN1")
		(14 "In6.Cu" signal "GND2")
		(16 "In7.Cu" signal "IN2")
		(18 "In8.Cu" signal "GND3")
		(20 "In9.Cu" signal "IN3")
		(22 "In10.Cu" signal "GND4")
		(24 "In11.Cu" signal "IN4")
		(26 "In12.Cu" signal "GND5")
		(28 "In13.Cu" signal "IN5")
		(30 "In14.Cu" signal "GND6")
		(32 "In15.Cu" signal "IN6")
		(34 "In16.Cu" signal "GND7")
		(2 "B.Cu" signal "BOTTOM")
		(9 "F.Adhes" user "F.Adhesive")
		(11 "B.Adhes" user "B.Adhesive")
		(13 "F.Paste" user "Package Geometry/Pastemask Top")
		(15 "B.Paste" user "Package Geometry/Pastemask Bottom")
		(5 "F.SilkS" user "Ref Des/Silkscreen Top")
		(7 "B.SilkS" user "Ref Des/Silkscreen Bottom")
		(1 "F.Mask" user "Board Geometry/Soldermask Top")
		(3 "B.Mask" user "Board Geometry/Soldermask Bottom")
		(17 "Dwgs.User" user "User.Drawings")
		(19 "Cmts.User" user "User.Comments")
		(21 "Eco1.User" user "User.Eco1")
		(23 "Eco2.User" user "User.Eco2")
		(25 "Edge.Cuts" user "Board Geometry/Outline")
		(27 "Margin" user)
		(31 "F.CrtYd" user "Package Geometry/Place Bound Top")
		(29 "B.CrtYd" user "Package Geometry/Place Bound Bottom")
		(35 "F.Fab" user "Ref Des/Assembly Top")
		(33 "B.Fab" user "Ref Des/Assembly Bottom")
	)
	(footprint ""
		(layer "F.Cu")
		(at 407.949908 -295.89984)
		(property "Reference" "PEX3"
			(at -3.358642 35.5727 0)
			(unlocked yes)
			(layer "F.SilkS")
			(effects
				(font
					(size 2.032 1.524)
					(thickness 0.1524)
				)
				(justify left)
			)
		)
		(property "Value" ""
			(at 0 0 0)
			(layer "F.Fab")
			(effects
				(font
					(size 1.27 1.27)
				)
			)
		)
		(duplicate_pad_numbers_are_jumpers no)
		(pad "C22" smd circle
			(at -2.84988 -20.899882)
			(size 0.4572 0.4572)
			(layers "F.Cu" "F.Mask" "F.Paste")
			(net "P5E_PEX3_STN6_RX_DN<97>")
		)
		(pad "C23" smd circle
			(at -1.89992 -20.899882)
			(size 0.4572 0.4572)
			(layers "F.Cu" "F.Mask" "F.Paste")
			(net "GND")
		)
		(pad "C24" smd circle
			(at -0.94996 -20.899882)
			(size 0.4572 0.4572)
			(layers "F.Cu" "F.Mask" "F.Paste")
			(net "P5E_PEX3_STN5_RX_DN<80>")
		)
		(pad "C25" smd circle
			(at 0 -20.899882)
			(size 0.4572 0.4572)
			(layers "F.Cu" "F.Mask" "F.Paste")
			(net "GND")
		)
		(pad "C26" smd circle
			(at 0.94996 -20.899882)
			(size 0.4572 0.4572)
			(layers "F.Cu" "F.Mask" "F.Paste")
			(net "P5E_PEX3_STN5_RX_DN<82>")
		)
		(pad "C27" smd circle
			(at 1.89992 -20.899882)
			(size 0.4572 0.4572)
			(layers "F.Cu" "F.Mask" "F.Paste")
			(net "GND")
		)
		(pad "C28" smd circle
			(at 2.84988 -20.899882)
			(size 0.4572 0.4572)
			(layers "F.Cu" "F.Mask" "F.Paste")
			(net "P5E_PEX3_STN5_RX_DN<84>")
		)
		(pad "C29" smd circle
			(at 3.800094 -20.899882)
			(size 0.4572 0.4572)
			(layers "F.Cu" "F.Mask" "F.Paste")
			(net "GND")
		)
		(pad "C30" smd circle
			(at 4.750054 -20.899882)
			(size 0.4572 0.4572)
			(layers "F.Cu" "F.Mask" "F.Paste")
			(net "P5E_PEX3_STN5_RX_DN<86>")
		)
		(pad "C31" smd circle
			(at 5.700014 -20.899882)
			(size 0.4572 0.4572)
			(layers "F.Cu" "F.Mask" "F.Paste")
			(net "GND")
		)
		(pad "C32" smd circle
			(at 6.649974 -20.899882)
			(size 0.4572 0.4572)
			(layers "F.Cu" "F.Mask" "F.Paste")
			(net "P5E_PEX3_STN5_RX_DN<88>")
		)
		(pad "C33" smd circle
			(at 7.599934 -20.899882)
			(size 0.4572 0.4572)
			(layers "F.Cu" "F.Mask" "F.Paste")
			(net "GND")
		)
		(pad "C34" smd circle
			(at 8.549894 -20.899882)
			(size 0.4572 0.4572)
			(layers "F.Cu" "F.Mask" "F.Paste")
			(net "P5E_PEX3_STN5_RX_DN<90>")
		)
		(pad "C35" smd circle
			(at 9.500108 -20.899882)
			(size 0.4572 0.4572)
			(layers "F.Cu" "F.Mask" "F.Paste")
			(net "GND")
		)
		(pad "C36" smd circle
			(at 10.450068 -20.899882)
			(size 0.4572 0.4572)
			(layers "F.Cu" "F.Mask" "F.Paste")
			(net "P5E_PEX3_STN5_RX_DN<92>")
		)
		(pad "C37" smd circle
			(at 11.400028 -20.899882)
			(size 0.4572 0.4572)
			(layers "F.Cu" "F.Mask" "F.Paste")
			(net "GND")
		)
		(pad "C38" smd circle
			(at 12.349988 -20.899882)
			(size 0.4572 0.4572)
			(layers "F.Cu" "F.Mask" "F.Paste")
			(net "P5E_PEX3_STN5_RX_DN<94>")
		)
		(pad "C39" smd circle
			(at 13.299948 -20.899882)
			(size 0.4572 0.4572)
			(layers "F.Cu" "F.Mask" "F.Paste")
			(net "GND")
		)
		(pad "C40" smd circle
			(at 14.249908 -20.899882)
			(size 0.4572 0.4572)
			(layers "F.Cu" "F.Mask" "F.Paste")
			(net "P5E_PEX3_STN4_RX_DN<79>")
		)
		(pad "C41" smd circle
			(at 15.200122 -20.899882)
			(size 0.4572 0.4572)
			(layers "F.Cu" "F.Mask" "F.Paste")
			(net "GND")
		)
		(pad "C42" smd circle
			(at 16.150082 -20.899882)
			(size 0.4572 0.4572)
			(layers "F.Cu" "F.Mask" "F.Paste")
			(net "P5E_PEX3_STN4_RX_DN<77>")
		)
		(pad "C43" smd circle
			(at 17.100042 -20.899882)
			(size 0.4572 0.4572)
			(layers "F.Cu" "F.Mask" "F.Paste")
			(net "GND")
		)
		(pad "C44" smd circle
			(at 18.050002 -20.899882)
			(size 0.4572 0.4572)
			(layers "F.Cu" "F.Mask" "F.Paste")
			(net "P5E_PEX3_STN4_RX_DN<75>")
		)
		(pad "C45" smd circle
			(at 18.999962 -20.899882)
			(size 0.4572 0.4572)
			(layers "F.Cu" "F.Mask" "F.Paste")
			(net "GND")
		)
		(pad "C46" smd circle
			(at 19.949922 -20.899882)
			(size 0.4572 0.4572)
			(layers "F.Cu" "F.Mask" "F.Paste")
			(net "P5E_PEX3_STN4_RX_DN<73>")
		)
		(pad "C47" smd circle
			(at 20.899882 -20.899882)
			(size 0.4572 0.4572)
			(layers "F.Cu" "F.Mask" "F.Paste")
			(net "GND")
		)
		(pad "C48" smd circle
			(at 21.850096 -20.899882)
			(size 0.4572 0.4572)
			(layers "F.Cu" "F.Mask" "F.Paste")
			(net "P5E_PEX3_STN4_RX_DP<71>")
		)
		(pad "C49" smd circle
			(at 22.800056 -20.899882)
			(size 0.4572 0.4572)
			(layers "F.Cu" "F.Mask" "F.Paste")
			(net "P5E_PEX3_STN4_RX_DN<71>")
		)
		(pad "D1" smd circle
			(at -22.800056 -19.949922)
			(size 0.4572 0.4572)
			(layers "F.Cu" "F.Mask" "F.Paste")
			(net "GND")
		)
		(pad "D2" smd circle
			(at -21.850096 -19.949922)
			(size 0.4572 0.4572)
			(layers "F.Cu" "F.Mask" "F.Paste")
			(net "GND")
		)
		(pad "D3" smd circle
			(at -20.899882 -19.949922)
			(size 0.4572 0.4572)
			(layers "F.Cu" "F.Mask" "F.Paste")
			(net "GND")
		)
		(pad "D4" smd circle
			(at -19.949922 -19.949922)
			(size 0.4572 0.4572)
			(layers "F.Cu" "F.Mask" "F.Paste")
			(net "P5E_PEX3_STN7_RX_DP<124>")
		)
		(pad "D5" smd circle
			(at -18.999962 -19.949922)
			(size 0.4572 0.4572)
			(layers "F.Cu" "F.Mask" "F.Paste")
			(net "GND")
		)
		(pad "D6" smd circle
			(at -18.050002 -19.949922)
			(size 0.4572 0.4572)
			(layers "F.Cu" "F.Mask" "F.Paste")
			(net "P5E_PEX3_STN7_RX_DP<126>")
		)
		(pad "D7" smd circle
			(at -17.100042 -19.949922)
			(size 0.4572 0.4572)
			(layers "F.Cu" "F.Mask" "F.Paste")
			(net "GND")
		)
		(pad "D8" smd circle
			(at -16.150082 -19.949922)
			(size 0.4572 0.4572)
			(layers "F.Cu" "F.Mask" "F.Paste")
			(net "P5E_PEX3_STN6_RX_DP<111>")
		)
		(pad "D9" smd circle
			(at -15.200122 -19.949922)
			(size 0.4572 0.4572)
			(layers "F.Cu" "F.Mask" "F.Paste")
			(net "GND")
		)
		(pad "D10" smd circle
			(at -14.249908 -19.949922)
			(size 0.4572 0.4572)
			(layers "F.Cu" "F.Mask" "F.Paste")
			(net "P5E_PEX3_STN6_RX_DP<109>")
		)
		(pad "D11" smd circle
			(at -13.299948 -19.949922)
			(size 0.4572 0.4572)
			(layers "F.Cu" "F.Mask" "F.Paste")
			(net "GND")
		)
		(pad "D12" smd circle
			(at -12.349988 -19.949922)
			(size 0.4572 0.4572)
			(layers "F.Cu" "F.Mask" "F.Paste")
			(net "P5E_PEX3_STN6_RX_DP<107>")
		)
		(pad "D13" smd circle
			(at -11.400028 -19.949922)
			(size 0.4572 0.4572)
			(layers "F.Cu" "F.Mask" "F.Paste")
			(net "GND")
		)
		(pad "D14" smd circle
			(at -10.450068 -19.949922)
			(size 0.4572 0.4572)
			(layers "F.Cu" "F.Mask" "F.Paste")
			(net "P5E_PEX3_STN6_RX_DP<105>")
		)
		(pad "D15" smd circle
			(at -9.500108 -19.949922)
			(size 0.4572 0.4572)
			(layers "F.Cu" "F.Mask" "F.Paste")
			(net "GND")
		)
		(pad "D16" smd circle
			(at -8.549894 -19.949922)
			(size 0.4572 0.4572)
			(layers "F.Cu" "F.Mask" "F.Paste")
			(net "P5E_PEX3_STN6_RX_DP<103>")
		)
		(pad "D17" smd circle
			(at -7.599934 -19.949922)
			(size 0.4572 0.4572)
			(layers "F.Cu" "F.Mask" "F.Paste")
			(net "GND")
		)
		(pad "D18" smd circle
			(at -6.649974 -19.949922)
			(size 0.4572 0.4572)
			(layers "F.Cu" "F.Mask" "F.Paste")
			(net "P5E_PEX3_STN6_RX_DP<101>")
		)
		(pad "D19" smd circle
			(at -5.700014 -19.949922)
			(size 0.4572 0.4572)
			(layers "F.Cu" "F.Mask" "F.Paste")
			(net "GND")
		)
		(pad "D20" smd circle
			(at -4.750054 -19.949922)
			(size 0.4572 0.4572)
			(layers "F.Cu" "F.Mask" "F.Paste")
			(net "P5E_PEX3_STN6_RX_DP<99>")
		)
		(pad "D21" smd circle
			(at -3.800094 -19.949922)
			(size 0.4572 0.4572)
			(layers "F.Cu" "F.Mask" "F.Paste")
			(net "GND")
		)
		(pad "D22" smd circle
			(at -2.84988 -19.949922)
			(size 0.4572 0.4572)
			(layers "F.Cu" "F.Mask" "F.Paste")
			(net "P5E_PEX3_STN6_RX_DP<97>")
		)
		(pad "D23" smd circle
			(at -1.89992 -19.949922)
			(size 0.4572 0.4572)
			(layers "F.Cu" "F.Mask" "F.Paste")
			(net "GND")
		)
		(pad "D24" smd circle
			(at -0.94996 -19.949922)
			(size 0.4572 0.4572)
			(layers "F.Cu" "F.Mask" "F.Paste")
			(net "P5E_PEX3_STN5_RX_DP<80>")
		)
		(pad "D25" smd circle
			(at 0 -19.949922)
			(size 0.4572 0.4572)
			(layers "F.Cu" "F.Mask" "F.Paste")
			(net "GND")
		)
		(pad "D26" smd circle
			(at 0.94996 -19.949922)
			(size 0.4572 0.4572)
			(layers "F.Cu" "F.Mask" "F.Paste")
			(net "P5E_PEX3_STN5_RX_DP<82>")
		)
		(pad "D27" smd circle
			(at 1.89992 -19.949922)
			(size 0.4572 0.4572)
			(layers "F.Cu" "F.Mask" "F.Paste")
			(net "GND")
		)
		(pad "D28" smd circle
			(at 2.84988 -19.949922)
			(size 0.4572 0.4572)
			(layers "F.Cu" "F.Mask" "F.Paste")
			(net "P5E_PEX3_STN5_RX_DP<84>")
		)
		(pad "D29" smd circle
			(at 3.800094 -19.949922)
			(size 0.4572 0.4572)
			(layers "F.Cu" "F.Mask" "F.Paste")
			(net "GND")
		)
		(pad "D30" smd circle
			(at 4.750054 -19.949922)
			(size 0.4572 0.4572)
			(layers "F.Cu" "F.Mask" "F.Paste")
			(net "P5E_PEX3_STN5_RX_DP<86>")
		)
		(pad "D31" smd circle
			(at 5.700014 -19.949922)
			(size 0.4572 0.4572)
			(layers "F.Cu" "F.Mask" "F.Paste")
			(net "GND")
		)
		(pad "D32" smd circle
			(at 6.649974 -19.949922)
			(size 0.4572 0.4572)
			(layers "F.Cu" "F.Mask" "F.Paste")
			(net "P5E_PEX3_STN5_RX_DP<88>")
		)
		(pad "D33" smd circle
			(at 7.599934 -19.949922)
			(size 0.4572 0.4572)
			(layers "F.Cu" "F.Mask" "F.Paste")
			(net "GND")
		)
		(pad "D34" smd circle
			(at 8.549894 -19.949922)
			(size 0.4572 0.4572)
			(layers "F.Cu" "F.Mask" "F.Paste")
			(net "P5E_PEX3_STN5_RX_DP<90>")
		)
		(pad "D35" smd circle
			(at 9.500108 -19.949922)
			(size 0.4572 0.4572)
			(layers "F.Cu" "F.Mask" "F.Paste")
			(net "GND")
		)
		(pad "D36" smd circle
			(at 10.450068 -19.949922)
			(size 0.4572 0.4572)
			(layers "F.Cu" "F.Mask" "F.Paste")
			(net "P5E_PEX3_STN5_RX_DP<92>")
		)
		(pad "D37" smd circle
			(at 11.400028 -19.949922)
			(size 0.4572 0.4572)
			(layers "F.Cu" "F.Mask" "F.Paste")
			(net "GND")
		)
		(pad "D38" smd circle
			(at 12.349988 -19.949922)
			(size 0.4572 0.4572)
			(layers "F.Cu" "F.Mask" "F.Paste")
			(net "P5E_PEX3_STN5_RX_DP<94>")
		)
		(pad "D39" smd circle
			(at 13.299948 -19.949922)
			(size 0.4572 0.4572)
			(layers "F.Cu" "F.Mask" "F.Paste")
			(net "GND")
		)
		(pad "D40" smd circle
			(at 14.249908 -19.949922)
			(size 0.4572 0.4572)
			(layers "F.Cu" "F.Mask" "F.Paste")
			(net "P5E_PEX3_STN4_RX_DP<79>")
		)
		(pad "D41" smd circle
			(at 15.200122 -19.949922)
			(size 0.4572 0.4572)
			(layers "F.Cu" "F.Mask" "F.Paste")
			(net "GND")
		)
		(pad "D42" smd circle
			(at 16.150082 -19.949922)
			(size 0.4572 0.4572)
			(layers "F.Cu" "F.Mask" "F.Paste")
			(net "P5E_PEX3_STN4_RX_DP<77>")
		)
		(pad "D43" smd circle
			(at 17.100042 -19.949922)
			(size 0.4572 0.4572)
			(layers "F.Cu" "F.Mask" "F.Paste")
			(net "GND")
		)
		(pad "D44" smd circle
			(at 18.050002 -19.949922)
			(size 0.4572 0.4572)
			(layers "F.Cu" "F.Mask" "F.Paste")
			(net "P5E_PEX3_STN4_RX_DP<75>")
		)
		(pad "D45" smd circle
			(at 18.999962 -19.949922)
			(size 0.4572 0.4572)
			(layers "F.Cu" "F.Mask" "F.Paste")
			(net "GND")
		)
		(pad "D46" smd circle
			(at 19.949922 -19.949922)
			(size 0.4572 0.4572)
			(layers "F.Cu" "F.Mask" "F.Paste")
			(net "P5E_PEX3_STN4_RX_DP<73>")
		)
		(pad "D47" smd circle
			(at 20.899882 -19.949922)
			(size 0.4572 0.4572)
			(layers "F.Cu" "F.Mask" "F.Paste")
			(net "GND")
		)
		(pad "D48" smd circle
			(at 21.850096 -19.949922)
			(size 0.4572 0.4572)
			(layers "F.Cu" "F.Mask" "F.Paste")
			(net "GND")
		)
		(pad "D49" smd circle
			(at 22.800056 -19.949922)
			(size 0.4572 0.4572)
			(layers "F.Cu" "F.Mask" "F.Paste")
			(net "GND")
		)
		(pad "E1" smd circle
			(at -22.800056 -18.999962)
			(size 0.4572 0.4572)
			(layers "F.Cu" "F.Mask" "F.Paste")
			(net "P5E_PEX3_STN7_TX_DN<122>")
		)
		(pad "E2" smd circle
			(at -21.850096 -18.999962)
			(size 0.4572 0.4572)
			(layers "F.Cu" "F.Mask" "F.Paste")
			(net "P5E_PEX3_STN7_TX_DP<122>")
		)
		(pad "E3" smd circle
			(at -20.899882 -18.999962)
			(size 0.4572 0.4572)
			(layers "F.Cu" "F.Mask" "F.Paste")
			(net "GND")
		)
		(pad "E4" smd circle
			(at -19.949922 -18.999962)
			(size 0.4572 0.4572)
			(layers "F.Cu" "F.Mask" "F.Paste")
			(net "GND")
		)
		(pad "E5" smd circle
			(at -18.999962 -18.999962)
			(size 0.4572 0.4572)
			(layers "F.Cu" "F.Mask" "F.Paste")
			(net "GND")
		)
		(pad "E6" smd circle
			(at -18.050002 -18.999962)
			(size 0.4572 0.4572)
			(layers "F.Cu" "F.Mask" "F.Paste")
			(net "GND")
		)
		(pad "E7" smd circle
			(at -17.100042 -18.999962)
			(size 0.4572 0.4572)
			(layers "F.Cu" "F.Mask" "F.Paste")
			(net "GND")
		)
		(pad "E8" smd circle
			(at -16.150082 -18.999962)
			(size 0.4572 0.4572)
			(layers "F.Cu" "F.Mask" "F.Paste")
			(net "GND")
		)
		(pad "E9" smd circle
			(at -15.200122 -18.999962)
			(size 0.4572 0.4572)
			(layers "F.Cu" "F.Mask" "F.Paste")
			(net "GND")
		)
		(pad "E10" smd circle
			(at -14.249908 -18.999962)
			(size 0.4572 0.4572)
			(layers "F.Cu" "F.Mask" "F.Paste")
			(net "GND")
		)
		(pad "E11" smd circle
			(at -13.299948 -18.999962)
			(size 0.4572 0.4572)
			(layers "F.Cu" "F.Mask" "F.Paste")
			(net "GND")
		)
		(pad "E12" smd circle
			(at -12.349988 -18.999962)
			(size 0.4572 0.4572)
			(layers "F.Cu" "F.Mask" "F.Paste")
			(net "GND")
		)
		(pad "E13" smd circle
			(at -11.400028 -18.999962)
			(size 0.4572 0.4572)
			(layers "F.Cu" "F.Mask" "F.Paste")
			(net "GND")
		)
		(pad "E14" smd circle
			(at -10.450068 -18.999962)
			(size 0.4572 0.4572)
			(layers "F.Cu" "F.Mask" "F.Paste")
			(net "GND")
		)
		(pad "E15" smd circle
			(at -9.500108 -18.999962)
			(size 0.4572 0.4572)
			(layers "F.Cu" "F.Mask" "F.Paste")
			(net "GND")
		)
		(pad "E16" smd circle
			(at -8.549894 -18.999962)
			(size 0.4572 0.4572)
			(layers "F.Cu" "F.Mask" "F.Paste")
			(net "GND")
		)
		(pad "E17" smd circle
			(at -7.599934 -18.999962)
			(size 0.4572 0.4572)
			(layers "F.Cu" "F.Mask" "F.Paste")
			(net "GND")
		)
		(pad "E18" smd circle
			(at -6.649974 -18.999962)
			(size 0.4572 0.4572)
			(layers "F.Cu" "F.Mask" "F.Paste")
			(net "GND")
		)
		(pad "E19" smd circle
			(at -5.700014 -18.999962)
			(size 0.4572 0.4572)
			(layers "F.Cu" "F.Mask" "F.Paste")
			(net "GND")
		)
		(pad "E20" smd circle
			(at -4.750054 -18.999962)
			(size 0.4572 0.4572)
			(layers "F.Cu" "F.Mask" "F.Paste")
			(net "GND")
		)
		(pad "E21" smd circle
			(at -3.800094 -18.999962)
			(size 0.4572 0.4572)
			(layers "F.Cu" "F.Mask" "F.Paste")
			(net "GND")
		)
		(pad "E22" smd circle
			(at -2.84988 -18.999962)
			(size 0.4572 0.4572)
			(layers "F.Cu" "F.Mask" "F.Paste")
			(net "GND")
		)
		(pad "E23" smd circle
			(at -1.89992 -18.999962)
			(size 0.4572 0.4572)
			(layers "F.Cu" "F.Mask" "F.Paste")
			(net "GND")
		)
		(pad "E24" smd circle
			(at -0.94996 -18.999962)
			(size 0.4572 0.4572)
			(layers "F.Cu" "F.Mask" "F.Paste")
			(net "GND")
		)
		(pad "E25" smd circle
			(at 0 -18.999962)
			(size 0.4572 0.4572)
			(layers "F.Cu" "F.Mask" "F.Paste")
			(net "GND")
		)
		(pad "E26" smd circle
			(at 0.94996 -18.999962)
			(size 0.4572 0.4572)
			(layers "F.Cu" "F.Mask" "F.Paste")
			(net "GND")
		)
		(pad "E27" smd circle
			(at 1.89992 -18.999962)
			(size 0.4572 0.4572)
			(layers "F.Cu" "F.Mask" "F.Paste")
			(net "GND")
		)
		(pad "E28" smd circle
			(at 2.84988 -18.999962)
			(size 0.4572 0.4572)
			(layers "F.Cu" "F.Mask" "F.Paste")
			(net "GND")
		)
		(pad "E29" smd circle
			(at 3.800094 -18.999962)
			(size 0.4572 0.4572)
			(layers "F.Cu" "F.Mask" "F.Paste")
			(net "GND")
		)
		(pad "E30" smd circle
			(at 4.750054 -18.999962)
			(size 0.4572 0.4572)
			(layers "F.Cu" "F.Mask" "F.Paste")
			(net "GND")
		)
		(pad "E31" smd circle
			(at 5.700014 -18.999962)
			(size 0.4572 0.4572)
			(layers "F.Cu" "F.Mask" "F.Paste")
			(net "GND")
		)
		(pad "E32" smd circle
			(at 6.649974 -18.999962)
			(size 0.4572 0.4572)
			(layers "F.Cu" "F.Mask" "F.Paste")
			(net "GND")
		)
		(pad "E33" smd circle
			(at 7.599934 -18.999962)
			(size 0.4572 0.4572)
			(layers "F.Cu" "F.Mask" "F.Paste")
			(net "GND")
		)
		(pad "E34" smd circle
			(at 8.549894 -18.999962)
			(size 0.4572 0.4572)
			(layers "F.Cu" "F.Mask" "F.Paste")
			(net "GND")
		)
		(pad "E35" smd circle
			(at 9.500108 -18.999962)
			(size 0.4572 0.4572)
			(layers "F.Cu" "F.Mask" "F.Paste")
			(net "GND")
		)
		(pad "E36" smd circle
			(at 10.450068 -18.999962)
			(size 0.4572 0.4572)
			(layers "F.Cu" "F.Mask" "F.Paste")
			(net "GND")
		)
		(pad "E37" smd circle
			(at 11.400028 -18.999962)
			(size 0.4572 0.4572)
			(layers "F.Cu" "F.Mask" "F.Paste")
			(net "GND")
		)
		(pad "E38" smd circle
			(at 12.349988 -18.999962)
			(size 0.4572 0.4572)
			(layers "F.Cu" "F.Mask" "F.Paste")
			(net "GND")
		)
		(pad "E39" smd circle
			(at 13.299948 -18.999962)
			(size 0.4572 0.4572)
			(layers "F.Cu" "F.Mask" "F.Paste")
			(net "GND")
		)
		(pad "E40" smd circle
			(at 14.249908 -18.999962)
			(size 0.4572 0.4572)
			(layers "F.Cu" "F.Mask" "F.Paste")
			(net "GND")
		)
	)
)
